(kicad_pcb
	(version 20260206)
	(generator "pcbnew")
	(generator_version "10.0")
	(general
		(thickness 1.6)
		(legacy_teardrops no)
	)
	(paper "A4")
	(title_block
		(title "Wiwynn_Tioga_Pass_MB.brd")
		(comment 1 "Tioga Pass / footprints 4130-4137 of 4770")
	)
	(layers
		(0 "F.Cu" signal "TOP")
		(4 "In1.Cu" signal "L2GND")
		(6 "In2.Cu" signal "L3")
		(8 "In3.Cu" signal "L4GND")
		(10 "In4.Cu" signal "L5")
		(12 "In5.Cu" signal "L6GND")
		(14 "In6.Cu" signal "L7VCC")
		(16 "In7.Cu" signal "L8VCC")
		(18 "In8.Cu" signal "L9GND")
		(20 "In9.Cu" signal "L10")
		(22 "In10.Cu" signal "L11GND")
		(24 "In11.Cu" signal "L12")
		(26 "In12.Cu" signal "L13GND")
		(2 "B.Cu" signal "BOTTOM")
		(9 "F.Adhes" user "F.Adhesive")
		(11 "B.Adhes" user "B.Adhesive")
		(13 "F.Paste" user "Package Geometry/Pastemask Top")
		(15 "B.Paste" user "Package Geometry/Pastemask Bottom")
		(5 "F.SilkS" user "Ref Des/Silkscreen Top")
		(7 "B.SilkS" user "Ref Des/Silkscreen Bottom")
		(1 "F.Mask" user "Board Geometry/Soldermask Top")
		(3 "B.Mask" user "Board Geometry/Soldermask Bottom")
		(17 "Dwgs.User" user "User.Drawings")
		(19 "Cmts.User" user "User.Comments")
		(21 "Eco1.User" user "User.Eco1")
		(23 "Eco2.User" user "User.Eco2")
		(25 "Edge.Cuts" user "Board Geometry/Outline")
		(27 "Margin" user)
		(31 "F.CrtYd" user "Package Geometry/Place Bound Top")
		(29 "B.CrtYd" user "Package Geometry/Place Bound Bottom")
		(35 "F.Fab" user "Ref Des/Assembly Top")
		(33 "B.Fab" user "Ref Des/Assembly Bottom")
	)
	(footprint ""
		(layer "B.Cu")
		(at 104.5591 -140.208 90)
		(property "Reference" "C5G107"
			(at -1.14681 0.76708 180)
			(unlocked yes)
			(layer "B.SilkS")
			(effects
				(font
					(size 0.7874 0.5842)
					(thickness 0.1524)
				)
				(justify mirror)
			)
		)
		(property "Value" ""
			(at 0 0 90)
			(layer "B.Fab")
			(effects
				(font
					(size 1.27 1.27)
				)
				(justify mirror)
			)
		)
		(duplicate_pad_numbers_are_jumpers no)
		(fp_rect
			(start -0.4953 -0.2032)
			(end 0.4953 1.6002)
			(stroke
				(width 0)
				(type default)
			)
			(fill no)
			(layer "B.CrtYd")
		)
		(fp_line
			(start 0.4953 -0.2032)
			(end -0.4953 -0.2032)
			(stroke
				(width 0.1)
				(type default)
			)
			(layer "B.Fab")
		)
		(fp_line
			(start -0.4953 -0.2032)
			(end -0.4953 1.6002)
			(stroke
				(width 0.1)
				(type default)
			)
			(layer "B.Fab")
		)
		(fp_line
			(start 0.4953 1.6002)
			(end 0.4953 -0.2032)
			(stroke
				(width 0.1)
				(type default)
			)
			(layer "B.Fab")
		)
		(fp_line
			(start -0.4953 1.6002)
			(end 0.4953 1.6002)
			(stroke
				(width 0.1)
				(type default)
			)
			(layer "B.Fab")
		)
		(pad "1" smd rect
			(at 0 0 270)
			(size 0.762 0.889)
			(layers "B.Cu" "B.Mask" "B.Paste")
			(net "PVDDQ_KLM")
		)
		(pad "2" smd rect
			(at 0 1.397 270)
			(size 0.762 0.889)
			(layers "B.Cu" "B.Mask" "B.Paste")
			(net "GND")
		)
		(zone
			(layer "B.Cu")
			(hatch none 0.5)
			(connect_pads
				(clearance 0)
			)
			(min_thickness 0.25)
			(keepout
				(tracks not_allowed)
				(vias allowed)
				(pads allowed)
				(copperpour not_allowed)
				(footprints allowed)
			)
			(placement
				(enabled no)
				(sheetname "")
			)
			(fill
				(thermal_gap 0.5)
				(thermal_bridge_width 0.5)
				(island_removal_mode 0)
			)
			(polygon
				(pts
					(xy 105.0036 -139.827) (xy 105.5116 -139.827) (xy 105.5116 -140.589) (xy 105.0036 -140.589)
				)
			)
		)
	)
	(footprint ""
		(layer "B.Cu")
		(at 466.1535 -4.445 90)
		(property "Reference" "R2U50"
			(at 0 0 90)
			(layer "B.SilkS")
			(hide yes)
			(effects
				(font
					(size 1.27 1.27)
				)
				(justify mirror)
			)
		)
		(property "Value" ""
			(at 0 0 90)
			(layer "B.Fab")
			(effects
				(font
					(size 1.27 1.27)
				)
				(justify mirror)
			)
		)
		(duplicate_pad_numbers_are_jumpers no)
		(fp_poly
			(pts
				(xy 0.2794 -0.1016) (xy -0.2794 -0.1016) (xy -0.2794 0.9906) (xy 0.2794 0.9906)
			)
			(stroke
				(width 0)
				(type default)
			)
			(fill no)
			(layer "B.CrtYd")
		)
		(fp_line
			(start 0.2794 -0.1016)
			(end 0.2794 0.9906)
			(stroke
				(width 0.1)
				(type default)
			)
			(layer "B.Fab")
		)
		(fp_line
			(start -0.2794 -0.1016)
			(end 0.2794 -0.1016)
			(stroke
				(width 0.1)
				(type default)
			)
			(layer "B.Fab")
		)
		(fp_line
			(start 0.2794 0.9906)
			(end -0.2794 0.9906)
			(stroke
				(width 0.1)
				(type default)
			)
			(layer "B.Fab")
		)
		(fp_line
			(start -0.2794 0.9906)
			(end -0.2794 -0.1016)
			(stroke
				(width 0.1)
				(type default)
			)
			(layer "B.Fab")
		)
		(pad "1" smd rect
			(at 0 0 270)
			(size 0.508 0.508)
			(layers "B.Cu" "B.Mask" "B.Paste")
			(net "FM_SLT_CFG2_R")
		)
		(pad "2" smd rect
			(at 0 0.889 270)
			(size 0.508 0.508)
			(layers "B.Cu" "B.Mask" "B.Paste")
			(net "FM_PWRBRK_SLOT_N")
		)
		(zone
			(layer "B.Cu")
			(hatch none 0.5)
			(connect_pads
				(clearance 0)
			)
			(min_thickness 0.25)
			(keepout
				(tracks allowed)
				(vias not_allowed)
				(pads allowed)
				(copperpour not_allowed)
				(footprints allowed)
			)
			(placement
				(enabled no)
				(sheetname "")
			)
			(fill
				(thermal_gap 0.5)
				(thermal_bridge_width 0.5)
				(island_removal_mode 0)
			)
			(polygon
				(pts
					(xy 466.4075 -4.699) (xy 466.4075 -4.191) (xy 466.7885 -4.191) (xy 466.7885 -4.699)
				)
			)
		)
		(zone
			(layer "B.Cu")
			(hatch none 0.5)
			(connect_pads
				(clearance 0)
			)
			(min_thickness 0.25)
			(keepout
				(tracks not_allowed)
				(vias allowed)
				(pads allowed)
				(copperpour not_allowed)
				(footprints allowed)
			)
			(placement
				(enabled no)
				(sheetname "")
			)
			(fill
				(thermal_gap 0.5)
				(thermal_bridge_width 0.5)
				(island_removal_mode 0)
			)
			(polygon
				(pts
					(xy 466.7885 -4.699) (xy 466.7885 -4.191) (xy 466.4075 -4.191) (xy 466.4075 -4.699)
				)
			)
		)
	)
	(footprint ""
		(layer "B.Cu")
		(at 269.394686 -85.06714)
		(property "Reference" "C5P6"
			(at 0 0 0)
			(layer "B.SilkS")
			(hide yes)
			(effects
				(font
					(size 1.27 1.27)
				)
				(justify mirror)
			)
		)
		(property "Value" ""
			(at 0 0 0)
			(layer "B.Fab")
			(effects
				(font
					(size 1.27 1.27)
				)
				(justify mirror)
			)
		)
		(duplicate_pad_numbers_are_jumpers no)
		(fp_poly
			(pts
				(xy 0.7239 -0.2159) (xy -0.7239 -0.2159) (xy -0.7239 1.9939) (xy 0.7239 1.9939)
			)
			(stroke
				(width 0)
				(type default)
			)
			(fill no)
			(layer "B.CrtYd")
		)
		(fp_line
			(start -0.7239 -0.2159)
			(end 0.7239 -0.2159)
			(stroke
				(width 0.1)
				(type default)
			)
			(layer "B.Fab")
		)
		(fp_line
			(start -0.7239 1.9939)
			(end -0.7239 -0.2159)
			(stroke
				(width 0.1)
				(type default)
			)
			(layer "B.Fab")
		)
		(fp_line
			(start 0.7239 -0.2159)
			(end 0.7239 1.9939)
			(stroke
				(width 0.1)
				(type default)
			)
			(layer "B.Fab")
		)
		(fp_line
			(start 0.7239 1.9939)
			(end -0.7239 1.9939)
			(stroke
				(width 0.1)
				(type default)
			)
			(layer "B.Fab")
		)
		(pad "1" smd rect
			(at 0 0 180)
			(size 1.27 1.016)
			(layers "B.Cu" "B.Mask" "B.Paste")
			(net "PVDDQ_DEF")
		)
		(pad "2" smd rect
			(at 0 1.778 180)
			(size 1.27 1.016)
			(layers "B.Cu" "B.Mask" "B.Paste")
			(net "GND")
		)
		(zone
			(layer "B.Cu")
			(hatch none 0.5)
			(connect_pads
				(clearance 0)
			)
			(min_thickness 0.25)
			(keepout
				(tracks not_allowed)
				(vias allowed)
				(pads allowed)
				(copperpour not_allowed)
				(footprints allowed)
			)
			(placement
				(enabled no)
				(sheetname "")
			)
			(fill
				(thermal_gap 0.5)
				(thermal_bridge_width 0.5)
				(island_removal_mode 0)
			)
			(polygon
				(pts
					(xy 270.029686 -84.55914) (xy 268.759686 -84.55914) (xy 268.759686 -83.79714) (xy 270.029686 -83.79714)
				)
			)
		)
	)
	(footprint ""
		(layer "B.Cu")
		(at 16.256 -81.153 90)
		(property "Reference" "R9P15"
			(at 0 0 90)
			(layer "B.SilkS")
			(hide yes)
			(effects
				(font
					(size 1.27 1.27)
				)
				(justify mirror)
			)
		)
		(property "Value" ""
			(at 0 0 90)
			(layer "B.Fab")
			(effects
				(font
					(size 1.27 1.27)
				)
				(justify mirror)
			)
		)
		(duplicate_pad_numbers_are_jumpers no)
		(fp_poly
			(pts
				(xy 0.2794 -0.1016) (xy -0.2794 -0.1016) (xy -0.2794 0.9906) (xy 0.2794 0.9906)
			)
			(stroke
				(width 0)
				(type default)
			)
			(fill no)
			(layer "B.CrtYd")
		)
		(fp_line
			(start 0.2794 -0.1016)
			(end 0.2794 0.9906)
			(stroke
				(width 0.1)
				(type default)
			)
			(layer "B.Fab")
		)
		(fp_line
			(start -0.2794 -0.1016)
			(end 0.2794 -0.1016)
			(stroke
				(width 0.1)
				(type default)
			)
			(layer "B.Fab")
		)
		(fp_line
			(start 0.2794 0.9906)
			(end -0.2794 0.9906)
			(stroke
				(width 0.1)
				(type default)
			)
			(layer "B.Fab")
		)
		(fp_line
			(start -0.2794 0.9906)
			(end -0.2794 -0.1016)
			(stroke
				(width 0.1)
				(type default)
			)
			(layer "B.Fab")
		)
		(pad "1" smd rect
			(at 0 0 270)
			(size 0.508 0.508)
			(layers "B.Cu" "B.Mask" "B.Paste")
			(net "A_HSC_LOW_DRAIN")
		)
		(pad "2" smd rect
			(at 0 0.889 270)
			(size 0.508 0.508)
			(layers "B.Cu" "B.Mask" "B.Paste")
			(net "IRQ_OC_DETECT_N")
		)
		(zone
			(layer "B.Cu")
			(hatch none 0.5)
			(connect_pads
				(clearance 0)
			)
			(min_thickness 0.25)
			(keepout
				(tracks allowed)
				(vias not_allowed)
				(pads allowed)
				(copperpour not_allowed)
				(footprints allowed)
			)
			(placement
				(enabled no)
				(sheetname "")
			)
			(fill
				(thermal_gap 0.5)
				(thermal_bridge_width 0.5)
				(island_removal_mode 0)
			)
			(polygon
				(pts
					(xy 16.51 -81.407) (xy 16.51 -80.899) (xy 16.891 -80.899) (xy 16.891 -81.407)
				)
			)
		)
		(zone
			(layer "B.Cu")
			(hatch none 0.5)
			(connect_pads
				(clearance 0)
			)
			(min_thickness 0.25)
			(keepout
				(tracks not_allowed)
				(vias allowed)
				(pads allowed)
				(copperpour not_allowed)
				(footprints allowed)
			)
			(placement
				(enabled no)
				(sheetname "")
			)
			(fill
				(thermal_gap 0.5)
				(thermal_bridge_width 0.5)
				(island_removal_mode 0)
			)
			(polygon
				(pts
					(xy 16.891 -81.407) (xy 16.891 -80.899) (xy 16.51 -80.899) (xy 16.51 -81.407)
				)
			)
		)
	)
	(footprint ""
		(layer "B.Cu")
		(at 375.0945 -44.9072 90)
		(property "Reference" "C2T32"
			(at 0 0 90)
			(layer "B.SilkS")
			(hide yes)
			(effects
				(font
					(size 1.27 1.27)
				)
				(justify mirror)
			)
		)
		(property "Value" ""
			(at 0 0 90)
			(layer "B.Fab")
			(effects
				(font
					(size 1.27 1.27)
				)
				(justify mirror)
			)
		)
		(duplicate_pad_numbers_are_jumpers no)
		(fp_poly
			(pts
				(xy -0.3048 -0.1016) (xy -0.3048 0.9906) (xy 0.3048 0.9906) (xy 0.3048 -0.1016)
			)
			(stroke
				(width 0)
				(type default)
			)
			(fill no)
			(layer "B.CrtYd")
		)
		(fp_line
			(start 0.3048 -0.1016)
			(end 0.3048 0.9906)
			(stroke
				(width 0.1)
				(type default)
			)
			(layer "B.Fab")
		)
		(fp_line
			(start -0.3048 -0.1016)
			(end 0.3048 -0.1016)
			(stroke
				(width 0.1)
				(type default)
			)
			(layer "B.Fab")
		)
		(fp_line
			(start 0.3048 0.9906)
			(end -0.3048 0.9906)
			(stroke
				(width 0.1)
				(type default)
			)
			(layer "B.Fab")
		)
		(fp_line
			(start -0.3048 0.9906)
			(end -0.3048 -0.1016)
			(stroke
				(width 0.1)
				(type default)
			)
			(layer "B.Fab")
		)
		(pad "1" smd rect
			(at 0 0 270)
			(size 0.508 0.508)
			(layers "B.Cu" "B.Mask" "B.Paste")
			(net "P0V7_GTL2104_5_VREF")
		)
		(pad "2" smd rect
			(at 0 0.889 270)
			(size 0.508 0.508)
			(layers "B.Cu" "B.Mask" "B.Paste")
			(net "GND")
		)
		(zone
			(layer "B.Cu")
			(hatch none 0.5)
			(connect_pads
				(clearance 0)
			)
			(min_thickness 0.25)
			(keepout
				(tracks allowed)
				(vias not_allowed)
				(pads allowed)
				(copperpour not_allowed)
				(footprints allowed)
			)
			(placement
				(enabled no)
				(sheetname "")
			)
			(fill
				(thermal_gap 0.5)
				(thermal_bridge_width 0.5)
				(island_removal_mode 0)
			)
			(polygon
				(pts
					(xy 375.3485 -45.1612) (xy 375.3485 -44.6532) (xy 375.7295 -44.6532) (xy 375.7295 -45.1612)
				)
			)
		)
		(zone
			(layer "B.Cu")
			(hatch none 0.5)
			(connect_pads
				(clearance 0)
			)
			(min_thickness 0.25)
			(keepout
				(tracks not_allowed)
				(vias allowed)
				(pads allowed)
				(copperpour not_allowed)
				(footprints allowed)
			)
			(placement
				(enabled no)
				(sheetname "")
			)
			(fill
				(thermal_gap 0.5)
				(thermal_bridge_width 0.5)
				(island_removal_mode 0)
			)
			(polygon
				(pts
					(xy 375.7295 -45.1612) (xy 375.7295 -44.6532) (xy 375.3485 -44.6532) (xy 375.3485 -45.1612)
				)
			)
		)
	)
	(footprint ""
		(layer "B.Cu")
		(at 418.846 -23.495 90)
		(property "Reference" "L25W2"
			(at 0 0 90)
			(layer "B.SilkS")
			(hide yes)
			(effects
				(font
					(size 1.27 1.27)
				)
				(justify mirror)
			)
		)
		(property "Value" "*"
			(at -0.0254 -2.8829 90)
			(unlocked yes)
			(layer "B.Fab")
			(hide yes)
			(effects
				(font
					(size 1.27 1.016)
					(thickness 0.1524)
				)
				(justify mirror)
			)
		)
		(property "Device Type" "IND-68NH-15-GP_DISCRET-GC1-INDA"
			(at -0.0254 -4.4069 90)
			(unlocked yes)
			(layer "B.Fab")
			(hide yes)
			(effects
				(font
					(size 1.27 1.016)
					(thickness 0.1524)
				)
				(justify mirror)
			)
		)
		(duplicate_pad_numbers_are_jumpers no)
		(fp_line
			(start -0.254 0)
			(end 0.254 0)
			(stroke
				(width 0.2032)
				(type default)
			)
			(layer "B.SilkS")
		)
		(fp_rect
			(start 0.5842 1.3335)
			(end -0.5842 -1.3335)
			(stroke
				(width 0)
				(type default)
			)
			(fill no)
			(layer "B.CrtYd")
		)
		(fp_rect
			(start 0.5842 1.3335)
			(end -0.5842 -1.3335)
			(stroke
				(width 0)
				(type default)
			)
			(fill no)
			(layer "B.Fab")
		)
		(pad "1" smd custom
			(at 0 -0.762 270)
			(size 0.2159 0.2159)
			(layers "B.Cu" "B.Mask" "B.Paste")
			(net "BMC_VGA_GREEN")
			(options
				(clearance outline)
				(anchor circle)
			)
			(primitives
				(gr_poly
					(pts
						(arc
							(start -0.3302 0.4318)
							(mid -0.402042 0.402042)
							(end -0.4318 0.3302)
						)
						(arc
							(start -0.4318 -0.3302)
							(mid -0.402042 -0.402042)
							(end -0.3302 -0.4318)
						)
						(arc
							(start 0.3302 -0.4318)
							(mid 0.402042 -0.402042)
							(end 0.4318 -0.3302)
						)
						(arc
							(start 0.4318 0.3302)
							(mid 0.402042 0.402042)
							(end 0.3302 0.4318)
						)
					)
					(width 0)
					(fill yes)
				)
			)
		)
		(pad "2" smd custom
			(at 0 0.762 270)
			(size 0.2159 0.2159)
			(layers "B.Cu" "B.Mask" "B.Paste")
			(net "V_IO_G_J")
			(options
				(clearance outline)
				(anchor circle)
			)
			(primitives
				(gr_poly
					(pts
						(arc
							(start -0.3302 0.4318)
							(mid -0.402042 0.402042)
							(end -0.4318 0.3302)
						)
						(arc
							(start -0.4318 -0.3302)
							(mid -0.402042 -0.402042)
							(end -0.3302 -0.4318)
						)
						(arc
							(start 0.3302 -0.4318)
							(mid 0.402042 -0.402042)
							(end 0.4318 -0.3302)
						)
						(arc
							(start 0.4318 0.3302)
							(mid 0.402042 0.402042)
							(end 0.3302 0.4318)
						)
					)
					(width 0)
					(fill yes)
				)
			)
		)
	)
	(footprint ""
		(layer "B.Cu")
		(at 32.832802 -74.553064 90)
		(property "Reference" "C9P4"
			(at 0 0 90)
			(layer "B.SilkS")
			(hide yes)
			(effects
				(font
					(size 1.27 1.27)
				)
				(justify mirror)
			)
		)
		(property "Value" ""
			(at 0 0 90)
			(layer "B.Fab")
			(effects
				(font
					(size 1.27 1.27)
				)
				(justify mirror)
			)
		)
		(duplicate_pad_numbers_are_jumpers no)
		(fp_poly
			(pts
				(xy 0.7239 -0.2159) (xy -0.7239 -0.2159) (xy -0.7239 1.9939) (xy 0.7239 1.9939)
			)
			(stroke
				(width 0)
				(type default)
			)
			(fill no)
			(layer "B.CrtYd")
		)
		(fp_line
			(start 0.7239 -0.2159)
			(end 0.7239 1.9939)
			(stroke
				(width 0.1)
				(type default)
			)
			(layer "B.Fab")
		)
		(fp_line
			(start -0.7239 -0.2159)
			(end 0.7239 -0.2159)
			(stroke
				(width 0.1)
				(type default)
			)
			(layer "B.Fab")
		)
		(fp_line
			(start 0.7239 1.9939)
			(end -0.7239 1.9939)
			(stroke
				(width 0.1)
				(type default)
			)
			(layer "B.Fab")
		)
		(fp_line
			(start -0.7239 1.9939)
			(end -0.7239 -0.2159)
			(stroke
				(width 0.1)
				(type default)
			)
			(layer "B.Fab")
		)
		(pad "1" smd rect
			(at 0 0 270)
			(size 1.27 1.016)
			(layers "B.Cu" "B.Mask" "B.Paste")
			(net "VR_FET_SW_P12V_STBY_PVCCIN_CPU1")
		)
		(pad "2" smd rect
			(at 0 1.778 270)
			(size 1.27 1.016)
			(layers "B.Cu" "B.Mask" "B.Paste")
			(net "GND")
		)
		(zone
			(layer "B.Cu")
			(hatch none 0.5)
			(connect_pads
				(clearance 0)
			)
			(min_thickness 0.25)
			(keepout
				(tracks not_allowed)
				(vias allowed)
				(pads allowed)
				(copperpour not_allowed)
				(footprints allowed)
			)
			(placement
				(enabled no)
				(sheetname "")
			)
			(fill
				(thermal_gap 0.5)
				(thermal_bridge_width 0.5)
				(island_removal_mode 0)
			)
			(polygon
				(pts
					(xy 33.340802 -75.188064) (xy 33.340802 -73.918064) (xy 34.102802 -73.918064) (xy 34.102802 -75.188064)
				)
			)
		)
	)
	(footprint ""
		(layer "B.Cu")
		(at 198.760588 -85.687662 90)
		(property "Reference" "C4C14"
			(at 0 0 90)
			(layer "B.SilkS")
			(hide yes)
			(effects
				(font
					(size 1.27 1.27)
				)
				(justify mirror)
			)
		)
		(property "Value" "*"
			(at -1.1811 -2.8194 90)
			(unlocked yes)
			(layer "B.Fab")
			(hide yes)
			(effects
				(font
					(size 1.27 1.016)
					(thickness 0.1524)
				)
				(justify mirror)
			)
		)
		(property "Device Type" "SC1U10V2KX-4-GP_SMD-BCG6-SC1U1A"
			(at -1.1811 -4.3434 90)
			(unlocked yes)
			(layer "B.Fab")
			(hide yes)
			(effects
				(font
					(size 1.27 1.016)
					(thickness 0.1524)
				)
				(justify mirror)
			)
		)
		(duplicate_pad_numbers_are_jumpers no)
		(fp_rect
			(start 0.4318 0.9525)
			(end -0.4318 -0.9525)
			(stroke
				(width 0)
				(type default)
			)
			(fill no)
			(layer "B.CrtYd")
		)
		(fp_rect
			(start 0.4318 0.9525)
			(end -0.4318 -0.9525)
			(stroke
				(width 0)
				(type default)
			)
			(fill no)
			(layer "B.Fab")
		)
		(pad "1" smd custom
			(at 0 -0.4445 270)
			(size 0.1524 0.1524)
			(layers "B.Cu" "B.Mask" "B.Paste")
			(net "P5V_STBY")
			(options
				(clearance outline)
				(anchor circle)
			)
			(primitives
				(gr_poly
					(pts
						(arc
							(start 0.3048 0.2032)
							(mid 0.275042 0.275042)
							(end 0.2032 0.3048)
						)
						(arc
							(start -0.2032 0.3048)
							(mid -0.275042 0.275042)
							(end -0.3048 0.2032)
						)
						(arc
							(start -0.3048 -0.2032)
							(mid -0.275042 -0.275042)
							(end -0.2032 -0.3048)
						)
						(arc
							(start 0.2032 -0.3048)
							(mid 0.275042 -0.275042)
							(end 0.3048 -0.2032)
						)
					)
					(width 0)
					(fill yes)
				)
			)
		)
		(pad "2" smd custom
			(at 0 0.4445 270)
			(size 0.1524 0.1524)
			(layers "B.Cu" "B.Mask" "B.Paste")
			(net "GND")
			(options
				(clearance outline)
				(anchor circle)
			)
			(primitives
				(gr_poly
					(pts
						(arc
							(start 0.3048 0.2032)
							(mid 0.275042 0.275042)
							(end 0.2032 0.3048)
						)
						(arc
							(start -0.2032 0.3048)
							(mid -0.275042 0.275042)
							(end -0.3048 0.2032)
						)
						(arc
							(start -0.3048 -0.2032)
							(mid -0.275042 -0.275042)
							(end -0.2032 -0.3048)
						)
						(arc
							(start 0.2032 -0.3048)
							(mid 0.275042 -0.275042)
							(end 0.3048 -0.2032)
						)
					)
					(width 0)
					(fill yes)
				)
			)
		)
	)
)
